# T6G (Grand Teton) — schematic netlist excerpt (pin names and nets, part order shuffled) for the footprints in the layout excerpt that follows; sources: Cadence DE-HDL packaged netlist, KiCad conversion of 04192023_DAF0TMB3IC0_F0TG_MB_C_brd_V02_OCP.brd

C14  Q_CAP  0.1UF 25V 10% X7R  pkg 0402  page 125 : A = GPU_3V3IO_RSVD1_FFU_ISO ; B = GND
C5012  Q_CAP  1000PF 50V 5% X7R  pkg 0402  page 210 : A = PVDDCR_CPU0_P1_PMALERT ; B = GND

(kicad_pcb
	(version 20260206)
	(generator "pcbnew")
	(generator_version "10.0")
	(general
		(thickness 1.6)
		(legacy_teardrops no)
	)
	(paper "A4")
	(title_block
		(title "04192023_DAF0TMB3IC0_F0TG_MB_C_brd_V02_OCP.brd")
		(comment 1 "Grand Teton / footprints 6709-6710 of 8354")
	)
	(layers
		(0 "F.Cu" signal "TOP")
		(4 "In1.Cu" signal "GND")
		(6 "In2.Cu" signal "IN1")
		(8 "In3.Cu" signal "GND1")
		(10 "In4.Cu" signal "IN2")
		(12 "In5.Cu" signal "GND2")
		(14 "In6.Cu" signal "IN3")
		(16 "In7.Cu" signal "GND3")
		(18 "In8.Cu" signal "VCC")
		(20 "In9.Cu" signal "VCC1")
		(22 "In10.Cu" signal "GND4")
		(24 "In11.Cu" signal "IN4")
		(26 "In12.Cu" signal "GND5")
		(28 "In13.Cu" signal "IN5")
		(30 "In14.Cu" signal "GND6")
		(32 "In15.Cu" signal "IN6")
		(34 "In16.Cu" signal "GND7")
		(2 "B.Cu" signal "BOTTOM")
		(9 "F.Adhes" user "F.Adhesive")
		(11 "B.Adhes" user "B.Adhesive")
		(13 "F.Paste" user "Package Geometry/Pastemask Top")
		(15 "B.Paste" user "Package Geometry/Pastemask Bottom")
		(5 "F.SilkS" user "Ref Des/Silkscreen Top")
		(7 "B.SilkS" user "Ref Des/Silkscreen Bottom")
		(1 "F.Mask" user "Board Geometry/Soldermask Top")
		(3 "B.Mask" user "Board Geometry/Soldermask Bottom")
		(17 "Dwgs.User" user "User.Drawings")
		(19 "Cmts.User" user "User.Comments")
		(21 "Eco1.User" user "User.Eco1")
		(23 "Eco2.User" user "User.Eco2")
		(25 "Edge.Cuts" user "Board Geometry/Outline")
		(27 "Margin" user)
		(31 "F.CrtYd" user "Package Geometry/Place Bound Top")
		(29 "B.CrtYd" user "Package Geometry/Place Bound Bottom")
		(35 "F.Fab" user "Ref Des/Assembly Top")
		(33 "B.Fab" user "Ref Des/Assembly Bottom")
	)
	(footprint ""
		(layer "B.Cu")
		(at 90.209878 -139.80541 180)
		(property "Reference" "C5012"
			(at 0 0 0)
			(layer "B.SilkS")
			(hide yes)
			(effects
				(font
					(size 1.27 1.27)
				)
				(justify mirror)
			)
		)
		(property "Value" ""
			(at 0 0 0)
			(layer "B.Fab")
			(effects
				(font
					(size 1.27 1.27)
				)
				(justify mirror)
			)
		)
		(duplicate_pad_numbers_are_jumpers no)
		(fp_line
			(start 0.7874 0.4064)
			(end 0.7874 -0.4064)
			(stroke
				(width 0.1524)
				(type default)
			)
			(layer "B.SilkS")
		)
		(fp_line
			(start 0.7874 -0.4064)
			(end -0.7874 -0.4064)
			(stroke
				(width 0.1524)
				(type default)
			)
			(layer "B.SilkS")
		)
		(fp_line
			(start -0.7874 0.4064)
			(end 0.7874 0.4064)
			(stroke
				(width 0.1524)
				(type default)
			)
			(layer "B.SilkS")
		)
		(fp_line
			(start -0.7874 -0.4064)
			(end -0.7874 0.4064)
			(stroke
				(width 0.1524)
				(type default)
			)
			(layer "B.SilkS")
		)
		(fp_line
			(start 0.67945 0.3048)
			(end 0.67945 -0.305054)
			(stroke
				(width 0.1)
				(type default)
			)
			(layer "B.Fab")
		)
		(fp_line
			(start 0.67945 -0.305054)
			(end 0.12065 -0.305054)
			(stroke
				(width 0.1)
				(type default)
			)
			(layer "B.Fab")
		)
		(fp_line
			(start 0.12065 0.3048)
			(end 0.67945 0.3048)
			(stroke
				(width 0.1)
				(type default)
			)
			(layer "B.Fab")
		)
		(fp_line
			(start 0.12065 0.2794)
			(end 0.12065 0.3048)
			(stroke
				(width 0.1)
				(type default)
			)
			(layer "B.Fab")
		)
		(fp_line
			(start 0.12065 -0.2794)
			(end -0.12065 -0.2794)
			(stroke
				(width 0.1)
				(type default)
			)
			(layer "B.Fab")
		)
		(fp_line
			(start 0.12065 -0.305054)
			(end 0.12065 -0.2794)
			(stroke
				(width 0.1)
				(type default)
			)
			(layer "B.Fab")
		)
		(fp_line
			(start -0.120396 0.3048)
			(end -0.120396 0.2794)
			(stroke
				(width 0.1)
				(type default)
			)
			(layer "B.Fab")
		)
		(fp_line
			(start -0.120396 0.2794)
			(end 0.12065 0.2794)
			(stroke
				(width 0.1)
				(type default)
			)
			(layer "B.Fab")
		)
		(fp_line
			(start -0.12065 -0.2794)
			(end -0.12065 -0.3048)
			(stroke
				(width 0.1)
				(type default)
			)
			(layer "B.Fab")
		)
		(fp_line
			(start -0.12065 -0.3048)
			(end -0.67945 -0.3048)
			(stroke
				(width 0.1)
				(type default)
			)
			(layer "B.Fab")
		)
		(fp_line
			(start -0.67945 0.3048)
			(end -0.120396 0.3048)
			(stroke
				(width 0.1)
				(type default)
			)
			(layer "B.Fab")
		)
		(fp_line
			(start -0.67945 -0.3048)
			(end -0.67945 0.3048)
			(stroke
				(width 0.1)
				(type default)
			)
			(layer "B.Fab")
		)
		(pad "1" smd circle
			(at 0.40005 0)
			(size 0 0)
			(layers "B.Cu" "B.Mask" "B.Paste")
			(net "PVDDCR_CPU0_P1_PMALERT")
		)
		(pad "2" smd circle
			(at -0.40005 0)
			(size 0 0)
			(layers "B.Cu" "B.Mask" "B.Paste")
			(net "GND")
		)
	)
	(footprint ""
		(layer "B.Cu")
		(at 164.403532 -432.37658 -90)
		(property "Reference" "C14"
			(at 0 0 90)
			(layer "B.SilkS")
			(hide yes)
			(effects
				(font
					(size 1.27 1.27)
				)
				(justify mirror)
			)
		)
		(property "Value" ""
			(at 0 0 90)
			(layer "B.Fab")
			(effects
				(font
					(size 1.27 1.27)
				)
				(justify mirror)
			)
		)
		(duplicate_pad_numbers_are_jumpers no)
		(fp_line
			(start -0.7874 0.4064)
			(end 0.7874 0.4064)
			(stroke
				(width 0.1524)
				(type default)
			)
			(layer "B.SilkS")
		)
		(fp_line
			(start 0.7874 0.4064)
			(end 0.7874 -0.4064)
			(stroke
				(width 0.1524)
				(type default)
			)
			(layer "B.SilkS")
		)
		(fp_line
			(start -0.7874 -0.4064)
			(end -0.7874 0.4064)
			(stroke
				(width 0.1524)
				(type default)
			)
			(layer "B.SilkS")
		)
		(fp_line
			(start 0.7874 -0.4064)
			(end -0.7874 -0.4064)
			(stroke
				(width 0.1524)
				(type default)
			)
			(layer "B.SilkS")
		)
		(fp_line
			(start -0.67945 0.3048)
			(end -0.120396 0.3048)
			(stroke
				(width 0.1)
				(type default)
			)
			(layer "B.Fab")
		)
		(fp_line
			(start -0.120396 0.3048)
			(end -0.120396 0.2794)
			(stroke
				(width 0.1)
				(type default)
			)
			(layer "B.Fab")
		)
		(fp_line
			(start 0.12065 0.3048)
			(end 0.67945 0.3048)
			(stroke
				(width 0.1)
				(type default)
			)
			(layer "B.Fab")
		)
		(fp_line
			(start 0.67945 0.3048)
			(end 0.67945 -0.305054)
			(stroke
				(width 0.1)
				(type default)
			)
			(layer "B.Fab")
		)
		(fp_line
			(start -0.120396 0.2794)
			(end 0.12065 0.2794)
			(stroke
				(width 0.1)
				(type default)
			)
			(layer "B.Fab")
		)
		(fp_line
			(start 0.12065 0.2794)
			(end 0.12065 0.3048)
			(stroke
				(width 0.1)
				(type default)
			)
			(layer "B.Fab")
		)
		(fp_line
			(start -0.12065 -0.2794)
			(end -0.12065 -0.3048)
			(stroke
				(width 0.1)
				(type default)
			)
			(layer "B.Fab")
		)
		(fp_line
			(start 0.12065 -0.2794)
			(end -0.12065 -0.2794)
			(stroke
				(width 0.1)
				(type default)
			)
			(layer "B.Fab")
		)
		(fp_line
			(start -0.67945 -0.3048)
			(end -0.67945 0.3048)
			(stroke
				(width 0.1)
				(type default)
			)
			(layer "B.Fab")
		)
		(fp_line
			(start -0.12065 -0.3048)
			(end -0.67945 -0.3048)
			(stroke
				(width 0.1)
				(type default)
			)
			(layer "B.Fab")
		)
		(fp_line
			(start 0.12065 -0.305054)
			(end 0.12065 -0.2794)
			(stroke
				(width 0.1)
				(type default)
			)
			(layer "B.Fab")
		)
		(fp_line
			(start 0.67945 -0.305054)
			(end 0.12065 -0.305054)
			(stroke
				(width 0.1)
				(type default)
			)
			(layer "B.Fab")
		)
		(pad "1" smd circle
			(at 0.40005 0 90)
			(size 0 0)
			(layers "B.Cu" "B.Mask" "B.Paste")
			(net "GPU_3V3IO_RSVD1_FFU_ISO")
		)
		(pad "2" smd circle
			(at -0.40005 0 90)
			(size 0 0)
			(layers "B.Cu" "B.Mask" "B.Paste")
			(net "GND")
		)
	)
)
